(kicad_pcb
	(version 20260206)
	(generator "pcbnew")
	(generator_version "10.0")
	(general
		(thickness 1.6)
		(legacy_teardrops no)
	)
	(paper "A4")
	(title_block
		(title "12092022_DA0F0TFB6D0_F0T_FAN_BOARD_MP5048_D_brd_v02_OCP.brd")
		(comment 1 "Grand Teton / footprints 535-541 of 924")
	)
	(layers
		(0 "F.Cu" signal "TOP")
		(4 "In1.Cu" signal "GND")
		(6 "In2.Cu" signal "IN1")
		(8 "In3.Cu" signal "IN2")
		(10 "In4.Cu" signal "GND1")
		(2 "B.Cu" signal "BOTTOM")
		(9 "F.Adhes" user "F.Adhesive")
		(11 "B.Adhes" user "B.Adhesive")
		(13 "F.Paste" user "Package Geometry/Pastemask Top")
		(15 "B.Paste" user "Package Geometry/Pastemask Bottom")
		(5 "F.SilkS" user "Ref Des/Silkscreen Top")
		(7 "B.SilkS" user "Ref Des/Silkscreen Bottom")
		(1 "F.Mask" user "Board Geometry/Soldermask Top")
		(3 "B.Mask" user "Board Geometry/Soldermask Bottom")
		(17 "Dwgs.User" user "User.Drawings")
		(19 "Cmts.User" user "User.Comments")
		(21 "Eco1.User" user "User.Eco1")
		(23 "Eco2.User" user "User.Eco2")
		(25 "Edge.Cuts" user "Board Geometry/Outline")
		(27 "Margin" user)
		(31 "F.CrtYd" user "Package Geometry/Place Bound Top")
		(29 "B.CrtYd" user "Package Geometry/Place Bound Bottom")
		(35 "F.Fab" user "Ref Des/Assembly Top")
		(33 "B.Fab" user "Ref Des/Assembly Bottom")
	)
	(footprint ""
		(layer "F.Cu")
		(at 17.399 -203.073 180)
		(property "Reference" "U365"
			(at 1.397 -1.80467 0)
			(unlocked yes)
			(layer "F.SilkS")
			(effects
				(font
					(size 0.7874 0.5842)
					(thickness 0.1524)
				)
				(justify left)
			)
		)
		(property "Value" ""
			(at 0 0 180)
			(layer "F.Fab")
			(effects
				(font
					(size 1.27 1.27)
				)
			)
		)
		(duplicate_pad_numbers_are_jumpers no)
		(fp_line
			(start 1.335278 1.100074)
			(end 1.335278 -1.100074)
			(stroke
				(width 0.1524)
				(type default)
			)
			(layer "F.SilkS")
		)
		(fp_line
			(start 1.335278 -1.100074)
			(end -1.335278 -1.100074)
			(stroke
				(width 0.1524)
				(type default)
			)
			(layer "F.SilkS")
		)
		(fp_line
			(start -1.335278 1.100074)
			(end 1.335278 1.100074)
			(stroke
				(width 0.1524)
				(type default)
			)
			(layer "F.SilkS")
		)
		(fp_line
			(start -1.335278 -1.100074)
			(end -1.335278 1.100074)
			(stroke
				(width 0.1524)
				(type default)
			)
			(layer "F.SilkS")
		)
		(fp_line
			(start 0.674878 1.100074)
			(end 0.674878 -1.100074)
			(stroke
				(width 0.1)
				(type default)
			)
			(layer "F.Fab")
		)
		(fp_line
			(start 0.674878 -1.100074)
			(end -0.674878 -1.100074)
			(stroke
				(width 0.1)
				(type default)
			)
			(layer "F.Fab")
		)
		(fp_line
			(start -0.674878 1.100074)
			(end 0.674878 1.100074)
			(stroke
				(width 0.1)
				(type default)
			)
			(layer "F.Fab")
		)
		(fp_line
			(start -0.674878 -1.100074)
			(end -0.674878 1.100074)
			(stroke
				(width 0.1)
				(type default)
			)
			(layer "F.Fab")
		)
		(pad "D" smd rect
			(at 0.8001 0 90)
			(size 0.6096 0.8128)
			(layers "F.Cu" "F.Mask" "F.Paste")
			(net "FAN_6_FAIL_LED_R_N")
		)
		(pad "G" smd rect
			(at -0.8001 -0.649986 90)
			(size 0.6096 0.8128)
			(layers "F.Cu" "F.Mask" "F.Paste")
			(net "FAN_6_FAIL_R_LED")
		)
		(pad "S" smd rect
			(at -0.8001 0.649986 90)
			(size 0.6096 0.8128)
			(layers "F.Cu" "F.Mask" "F.Paste")
			(net "GND")
		)
	)
	(footprint ""
		(layer "F.Cu")
		(at 3.429 -126.111)
		(property "Reference" "C2026"
			(at 0 0 0)
			(layer "F.SilkS")
			(hide yes)
			(effects
				(font
					(size 1.27 1.27)
				)
			)
		)
		(property "Value" ""
			(at 0 0 0)
			(layer "F.Fab")
			(effects
				(font
					(size 1.27 1.27)
				)
			)
		)
		(duplicate_pad_numbers_are_jumpers no)
		(fp_line
			(start -1.524 -0.762)
			(end 1.524 -0.762)
			(stroke
				(width 0.1524)
				(type default)
			)
			(layer "F.SilkS")
		)
		(fp_line
			(start -1.524 0.762)
			(end -1.524 -0.762)
			(stroke
				(width 0.1524)
				(type default)
			)
			(layer "F.SilkS")
		)
		(fp_line
			(start 1.524 -0.762)
			(end 1.524 0.762)
			(stroke
				(width 0.1524)
				(type default)
			)
			(layer "F.SilkS")
		)
		(fp_line
			(start 1.524 0.762)
			(end -1.524 0.762)
			(stroke
				(width 0.1524)
				(type default)
			)
			(layer "F.SilkS")
		)
		(fp_line
			(start -1.1049 -0.724916)
			(end -1.1049 0.724916)
			(stroke
				(width 0.1)
				(type default)
			)
			(layer "F.Fab")
		)
		(fp_line
			(start -1.1049 0.724916)
			(end 1.1049 0.724916)
			(stroke
				(width 0.1)
				(type default)
			)
			(layer "F.Fab")
		)
		(fp_line
			(start 1.1049 -0.724916)
			(end -1.1049 -0.724916)
			(stroke
				(width 0.1)
				(type default)
			)
			(layer "F.Fab")
		)
		(fp_line
			(start 1.1049 0.724916)
			(end 1.1049 -0.724916)
			(stroke
				(width 0.1)
				(type default)
			)
			(layer "F.Fab")
		)
		(pad "1" smd rect
			(at -0.889 0 180)
			(size 1.016 1.27)
			(layers "F.Cu" "F.Mask" "F.Paste")
			(net "P12V_LED_FAN5")
		)
		(pad "2" smd rect
			(at 0.889 0 180)
			(size 1.016 1.27)
			(layers "F.Cu" "F.Mask" "F.Paste")
			(net "GND")
		)
	)
	(footprint ""
		(layer "F.Cu")
		(at 18.669 -288.036 180)
		(property "Reference" "R5320"
			(at 0 0 180)
			(layer "F.SilkS")
			(hide yes)
			(effects
				(font
					(size 1.27 1.27)
				)
			)
		)
		(property "Value" ""
			(at 0 0 180)
			(layer "F.Fab")
			(effects
				(font
					(size 1.27 1.27)
				)
			)
		)
		(duplicate_pad_numbers_are_jumpers no)
		(fp_line
			(start 1.2954 0.5842)
			(end -1.2954 0.5842)
			(stroke
				(width 0.1524)
				(type default)
			)
			(layer "F.SilkS")
		)
		(fp_line
			(start 1.2954 -0.5842)
			(end 1.2954 0.5842)
			(stroke
				(width 0.1524)
				(type default)
			)
			(layer "F.SilkS")
		)
		(fp_line
			(start -1.2954 0.5842)
			(end -1.2954 -0.5842)
			(stroke
				(width 0.1524)
				(type default)
			)
			(layer "F.SilkS")
		)
		(fp_line
			(start -1.2954 -0.5842)
			(end 1.2954 -0.5842)
			(stroke
				(width 0.1524)
				(type default)
			)
			(layer "F.SilkS")
		)
		(fp_line
			(start 1.1938 0.4064)
			(end 0.8636 0.4064)
			(stroke
				(width 0.1)
				(type default)
			)
			(layer "F.Fab")
		)
		(fp_line
			(start 1.1938 -0.406654)
			(end 1.1938 0.4064)
			(stroke
				(width 0.1)
				(type default)
			)
			(layer "F.Fab")
		)
		(fp_line
			(start 0.8636 0.4572)
			(end -0.8636 0.4572)
			(stroke
				(width 0.1)
				(type default)
			)
			(layer "F.Fab")
		)
		(fp_line
			(start 0.8636 0.4064)
			(end 0.8636 0.4572)
			(stroke
				(width 0.1)
				(type default)
			)
			(layer "F.Fab")
		)
		(fp_line
			(start 0.8636 -0.406654)
			(end 1.1938 -0.406654)
			(stroke
				(width 0.1)
				(type default)
			)
			(layer "F.Fab")
		)
		(fp_line
			(start 0.8636 -0.4572)
			(end 0.8636 -0.406654)
			(stroke
				(width 0.1)
				(type default)
			)
			(layer "F.Fab")
		)
		(fp_line
			(start -0.8636 0.4572)
			(end -0.8636 0.4318)
			(stroke
				(width 0.1)
				(type default)
			)
			(layer "F.Fab")
		)
		(fp_line
			(start -0.8636 0.4318)
			(end -0.8636 0.4064)
			(stroke
				(width 0.1)
				(type default)
			)
			(layer "F.Fab")
		)
		(fp_line
			(start -0.8636 0.4064)
			(end -1.1938 0.4064)
			(stroke
				(width 0.1)
				(type default)
			)
			(layer "F.Fab")
		)
		(fp_line
			(start -0.8636 -0.406654)
			(end -0.8636 -0.4572)
			(stroke
				(width 0.1)
				(type default)
			)
			(layer "F.Fab")
		)
		(fp_line
			(start -0.8636 -0.4572)
			(end 0.8636 -0.4572)
			(stroke
				(width 0.1)
				(type default)
			)
			(layer "F.Fab")
		)
		(fp_line
			(start -1.1938 0.4064)
			(end -1.1938 -0.406654)
			(stroke
				(width 0.1)
				(type default)
			)
			(layer "F.Fab")
		)
		(fp_line
			(start -1.1938 -0.406654)
			(end -0.8636 -0.406654)
			(stroke
				(width 0.1)
				(type default)
			)
			(layer "F.Fab")
		)
		(pad "1" smd rect
			(at -0.7366 0 90)
			(size 0.7112 0.8128)
			(layers "F.Cu" "F.Mask" "F.Paste")
			(net "P52V_FAN_7")
		)
		(pad "2" smd rect
			(at 0.7366 0 90)
			(size 0.7112 0.8128)
			(layers "F.Cu" "F.Mask" "F.Paste")
			(net "FAN_7_TACH_IL_R")
		)
	)
	(footprint ""
		(layer "F.Cu")
		(at 14.361922 -291.5031)
		(property "Reference" "R5241"
			(at 0 0 0)
			(layer "F.SilkS")
			(hide yes)
			(effects
				(font
					(size 1.27 1.27)
				)
			)
		)
		(property "Value" ""
			(at 0 0 0)
			(layer "F.Fab")
			(effects
				(font
					(size 1.27 1.27)
				)
			)
		)
		(duplicate_pad_numbers_are_jumpers no)
		(fp_line
			(start -0.7874 -0.4064)
			(end 0.7874 -0.4064)
			(stroke
				(width 0.1524)
				(type default)
			)
			(layer "F.SilkS")
		)
		(fp_line
			(start -0.7874 0.4064)
			(end -0.7874 -0.4064)
			(stroke
				(width 0.1524)
				(type default)
			)
			(layer "F.SilkS")
		)
		(fp_line
			(start 0.7874 -0.4064)
			(end 0.7874 0.4064)
			(stroke
				(width 0.1524)
				(type default)
			)
			(layer "F.SilkS")
		)
		(fp_line
			(start 0.7874 0.4064)
			(end -0.7874 0.4064)
			(stroke
				(width 0.1524)
				(type default)
			)
			(layer "F.SilkS")
		)
		(fp_line
			(start -0.67945 -0.305054)
			(end -0.12065 -0.305054)
			(stroke
				(width 0.1)
				(type default)
			)
			(layer "F.Fab")
		)
		(fp_line
			(start -0.67945 0.3048)
			(end -0.67945 -0.305054)
			(stroke
				(width 0.1)
				(type default)
			)
			(layer "F.Fab")
		)
		(fp_line
			(start -0.12065 -0.305054)
			(end -0.12065 -0.2794)
			(stroke
				(width 0.1)
				(type default)
			)
			(layer "F.Fab")
		)
		(fp_line
			(start -0.12065 -0.2794)
			(end 0.12065 -0.2794)
			(stroke
				(width 0.1)
				(type default)
			)
			(layer "F.Fab")
		)
		(fp_line
			(start -0.12065 0.2794)
			(end -0.12065 0.3048)
			(stroke
				(width 0.1)
				(type default)
			)
			(layer "F.Fab")
		)
		(fp_line
			(start -0.12065 0.3048)
			(end -0.67945 0.3048)
			(stroke
				(width 0.1)
				(type default)
			)
			(layer "F.Fab")
		)
		(fp_line
			(start 0.120396 0.2794)
			(end -0.12065 0.2794)
			(stroke
				(width 0.1)
				(type default)
			)
			(layer "F.Fab")
		)
		(fp_line
			(start 0.120396 0.3048)
			(end 0.120396 0.2794)
			(stroke
				(width 0.1)
				(type default)
			)
			(layer "F.Fab")
		)
		(fp_line
			(start 0.12065 -0.3048)
			(end 0.67945 -0.3048)
			(stroke
				(width 0.1)
				(type default)
			)
			(layer "F.Fab")
		)
		(fp_line
			(start 0.12065 -0.2794)
			(end 0.12065 -0.3048)
			(stroke
				(width 0.1)
				(type default)
			)
			(layer "F.Fab")
		)
		(fp_line
			(start 0.67945 -0.3048)
			(end 0.67945 0.3048)
			(stroke
				(width 0.1)
				(type default)
			)
			(layer "F.Fab")
		)
		(fp_line
			(start 0.67945 0.3048)
			(end 0.120396 0.3048)
			(stroke
				(width 0.1)
				(type default)
			)
			(layer "F.Fab")
		)
		(pad "1" smd circle
			(at -0.40005 0)
			(size 0 0)
			(layers "F.Cu" "F.Mask" "F.Paste")
			(net "FAN_7_PWM_IL_R")
		)
		(pad "2" smd circle
			(at 0.40005 0)
			(size 0 0)
			(layers "F.Cu" "F.Mask" "F.Paste")
			(net "FAN_7_PWM_IL")
		)
	)
	(footprint ""
		(layer "F.Cu")
		(at 43.561 -174.879)
		(property "Reference" "R5099"
			(at 0 0 0)
			(layer "F.SilkS")
			(hide yes)
			(effects
				(font
					(size 1.27 1.27)
				)
			)
		)
		(property "Value" ""
			(at 0 0 0)
			(layer "F.Fab")
			(effects
				(font
					(size 1.27 1.27)
				)
			)
		)
		(duplicate_pad_numbers_are_jumpers no)
		(fp_line
			(start -0.7874 -0.4064)
			(end 0.7874 -0.4064)
			(stroke
				(width 0.1524)
				(type default)
			)
			(layer "F.SilkS")
		)
		(fp_line
			(start -0.7874 0.4064)
			(end -0.7874 -0.4064)
			(stroke
				(width 0.1524)
				(type default)
			)
			(layer "F.SilkS")
		)
		(fp_line
			(start 0.7874 -0.4064)
			(end 0.7874 0.4064)
			(stroke
				(width 0.1524)
				(type default)
			)
			(layer "F.SilkS")
		)
		(fp_line
			(start 0.7874 0.4064)
			(end -0.7874 0.4064)
			(stroke
				(width 0.1524)
				(type default)
			)
			(layer "F.SilkS")
		)
		(fp_line
			(start -0.67945 -0.305054)
			(end -0.12065 -0.305054)
			(stroke
				(width 0.1)
				(type default)
			)
			(layer "F.Fab")
		)
		(fp_line
			(start -0.67945 0.3048)
			(end -0.67945 -0.305054)
			(stroke
				(width 0.1)
				(type default)
			)
			(layer "F.Fab")
		)
		(fp_line
			(start -0.12065 -0.305054)
			(end -0.12065 -0.2794)
			(stroke
				(width 0.1)
				(type default)
			)
			(layer "F.Fab")
		)
		(fp_line
			(start -0.12065 -0.2794)
			(end 0.12065 -0.2794)
			(stroke
				(width 0.1)
				(type default)
			)
			(layer "F.Fab")
		)
		(fp_line
			(start -0.12065 0.2794)
			(end -0.12065 0.3048)
			(stroke
				(width 0.1)
				(type default)
			)
			(layer "F.Fab")
		)
		(fp_line
			(start -0.12065 0.3048)
			(end -0.67945 0.3048)
			(stroke
				(width 0.1)
				(type default)
			)
			(layer "F.Fab")
		)
		(fp_line
			(start 0.120396 0.2794)
			(end -0.12065 0.2794)
			(stroke
				(width 0.1)
				(type default)
			)
			(layer "F.Fab")
		)
		(fp_line
			(start 0.120396 0.3048)
			(end 0.120396 0.2794)
			(stroke
				(width 0.1)
				(type default)
			)
			(layer "F.Fab")
		)
		(fp_line
			(start 0.12065 -0.3048)
			(end 0.67945 -0.3048)
			(stroke
				(width 0.1)
				(type default)
			)
			(layer "F.Fab")
		)
		(fp_line
			(start 0.12065 -0.2794)
			(end 0.12065 -0.3048)
			(stroke
				(width 0.1)
				(type default)
			)
			(layer "F.Fab")
		)
		(fp_line
			(start 0.67945 -0.3048)
			(end 0.67945 0.3048)
			(stroke
				(width 0.1)
				(type default)
			)
			(layer "F.Fab")
		)
		(fp_line
			(start 0.67945 0.3048)
			(end 0.120396 0.3048)
			(stroke
				(width 0.1)
				(type default)
			)
			(layer "F.Fab")
		)
		(pad "1" smd circle
			(at -0.40005 0)
			(size 0 0)
			(layers "F.Cu" "F.Mask" "F.Paste")
			(net "FAN_2_FAIL_LED")
		)
		(pad "2" smd circle
			(at 0.40005 0)
			(size 0 0)
			(layers "F.Cu" "F.Mask" "F.Paste")
			(net "FAN_2_FAIL_R_LED")
		)
	)
	(footprint ""
		(layer "F.Cu")
		(at 4.191 -170.815 180)
		(property "Reference" "R4859"
			(at 0 0 180)
			(layer "F.SilkS")
			(hide yes)
			(effects
				(font
					(size 1.27 1.27)
				)
			)
		)
		(property "Value" ""
			(at 0 0 180)
			(layer "F.Fab")
			(effects
				(font
					(size 1.27 1.27)
				)
			)
		)
		(duplicate_pad_numbers_are_jumpers no)
		(fp_line
			(start 0.7874 0.4064)
			(end -0.7874 0.4064)
			(stroke
				(width 0.1524)
				(type default)
			)
			(layer "F.SilkS")
		)
		(fp_line
			(start 0.7874 -0.4064)
			(end 0.7874 0.4064)
			(stroke
				(width 0.1524)
				(type default)
			)
			(layer "F.SilkS")
		)
		(fp_line
			(start -0.7874 0.4064)
			(end -0.7874 -0.4064)
			(stroke
				(width 0.1524)
				(type default)
			)
			(layer "F.SilkS")
		)
		(fp_line
			(start -0.7874 -0.4064)
			(end 0.7874 -0.4064)
			(stroke
				(width 0.1524)
				(type default)
			)
			(layer "F.SilkS")
		)
		(fp_line
			(start 0.67945 0.3048)
			(end 0.120396 0.3048)
			(stroke
				(width 0.1)
				(type default)
			)
			(layer "F.Fab")
		)
		(fp_line
			(start 0.67945 -0.3048)
			(end 0.67945 0.3048)
			(stroke
				(width 0.1)
				(type default)
			)
			(layer "F.Fab")
		)
		(fp_line
			(start 0.12065 -0.2794)
			(end 0.12065 -0.3048)
			(stroke
				(width 0.1)
				(type default)
			)
			(layer "F.Fab")
		)
		(fp_line
			(start 0.12065 -0.3048)
			(end 0.67945 -0.3048)
			(stroke
				(width 0.1)
				(type default)
			)
			(layer "F.Fab")
		)
		(fp_line
			(start 0.120396 0.3048)
			(end 0.120396 0.2794)
			(stroke
				(width 0.1)
				(type default)
			)
			(layer "F.Fab")
		)
		(fp_line
			(start 0.120396 0.2794)
			(end -0.12065 0.2794)
			(stroke
				(width 0.1)
				(type default)
			)
			(layer "F.Fab")
		)
		(fp_line
			(start -0.12065 0.3048)
			(end -0.67945 0.3048)
			(stroke
				(width 0.1)
				(type default)
			)
			(layer "F.Fab")
		)
		(fp_line
			(start -0.12065 0.2794)
			(end -0.12065 0.3048)
			(stroke
				(width 0.1)
				(type default)
			)
			(layer "F.Fab")
		)
		(fp_line
			(start -0.12065 -0.2794)
			(end 0.12065 -0.2794)
			(stroke
				(width 0.1)
				(type default)
			)
			(layer "F.Fab")
		)
		(fp_line
			(start -0.12065 -0.305054)
			(end -0.12065 -0.2794)
			(stroke
				(width 0.1)
				(type default)
			)
			(layer "F.Fab")
		)
		(fp_line
			(start -0.67945 0.3048)
			(end -0.67945 -0.305054)
			(stroke
				(width 0.1)
				(type default)
			)
			(layer "F.Fab")
		)
		(fp_line
			(start -0.67945 -0.305054)
			(end -0.12065 -0.305054)
			(stroke
				(width 0.1)
				(type default)
			)
			(layer "F.Fab")
		)
		(pad "1" smd circle
			(at -0.40005 0 180)
			(size 0 0)
			(layers "F.Cu" "F.Mask" "F.Paste")
			(net "FAN_5_PRSNT_BUF_R_N")
		)
		(pad "2" smd circle
			(at 0.40005 0 180)
			(size 0 0)
			(layers "F.Cu" "F.Mask" "F.Paste")
			(net "FAN_5_PRSNT_BUF_N")
		)
	)
	(footprint ""
		(layer "F.Cu")
		(at 13.335 -173.99 180)
		(property "Reference" "R5506"
			(at 0 0 180)
			(layer "F.SilkS")
			(hide yes)
			(effects
				(font
					(size 1.27 1.27)
				)
			)
		)
		(property "Value" ""
			(at 0 0 180)
			(layer "F.Fab")
			(effects
				(font
					(size 1.27 1.27)
				)
			)
		)
		(duplicate_pad_numbers_are_jumpers no)
		(fp_line
			(start 0.7874 0.4064)
			(end -0.7874 0.4064)
			(stroke
				(width 0.1524)
				(type default)
			)
			(layer "F.SilkS")
		)
		(fp_line
			(start 0.7874 -0.4064)
			(end 0.7874 0.4064)
			(stroke
				(width 0.1524)
				(type default)
			)
			(layer "F.SilkS")
		)
		(fp_line
			(start -0.7874 0.4064)
			(end -0.7874 -0.4064)
			(stroke
				(width 0.1524)
				(type default)
			)
			(layer "F.SilkS")
		)
		(fp_line
			(start -0.7874 -0.4064)
			(end 0.7874 -0.4064)
			(stroke
				(width 0.1524)
				(type default)
			)
			(layer "F.SilkS")
		)
		(fp_line
			(start 0.67945 0.3048)
			(end 0.120396 0.3048)
			(stroke
				(width 0.1)
				(type default)
			)
			(layer "F.Fab")
		)
		(fp_line
			(start 0.67945 -0.3048)
			(end 0.67945 0.3048)
			(stroke
				(width 0.1)
				(type default)
			)
			(layer "F.Fab")
		)
		(fp_line
			(start 0.12065 -0.2794)
			(end 0.12065 -0.3048)
			(stroke
				(width 0.1)
				(type default)
			)
			(layer "F.Fab")
		)
		(fp_line
			(start 0.12065 -0.3048)
			(end 0.67945 -0.3048)
			(stroke
				(width 0.1)
				(type default)
			)
			(layer "F.Fab")
		)
		(fp_line
			(start 0.120396 0.3048)
			(end 0.120396 0.2794)
			(stroke
				(width 0.1)
				(type default)
			)
			(layer "F.Fab")
		)
		(fp_line
			(start 0.120396 0.2794)
			(end -0.12065 0.2794)
			(stroke
				(width 0.1)
				(type default)
			)
			(layer "F.Fab")
		)
		(fp_line
			(start -0.12065 0.3048)
			(end -0.67945 0.3048)
			(stroke
				(width 0.1)
				(type default)
			)
			(layer "F.Fab")
		)
		(fp_line
			(start -0.12065 0.2794)
			(end -0.12065 0.3048)
			(stroke
				(width 0.1)
				(type default)
			)
			(layer "F.Fab")
		)
		(fp_line
			(start -0.12065 -0.2794)
			(end 0.12065 -0.2794)
			(stroke
				(width 0.1)
				(type default)
			)
			(layer "F.Fab")
		)
		(fp_line
			(start -0.12065 -0.305054)
			(end -0.12065 -0.2794)
			(stroke
				(width 0.1)
				(type default)
			)
			(layer "F.Fab")
		)
		(fp_line
			(start -0.67945 0.3048)
			(end -0.67945 -0.305054)
			(stroke
				(width 0.1)
				(type default)
			)
			(layer "F.Fab")
		)
		(fp_line
			(start -0.67945 -0.305054)
			(end -0.12065 -0.305054)
			(stroke
				(width 0.1)
				(type default)
			)
			(layer "F.Fab")
		)
		(pad "1" smd circle
			(at -0.40005 0 180)
			(size 0 0)
			(layers "F.Cu" "F.Mask" "F.Paste")
			(net "P3V3_AUX")
		)
		(pad "2" smd circle
			(at 0.40005 0 180)
			(size 0 0)
			(layers "F.Cu" "F.Mask" "F.Paste")
			(net "FAN_7_PRESENT_N")
		)
	)
)
